(kicad_pcb
	(version 20260206)
	(generator "pcbnew")
	(generator_version "10.0")
	(general
		(thickness 1.6)
		(legacy_teardrops no)
	)
	(paper "A4")
	(title_block
		(title "peb — Lightning_PEB_BRD.brd")
		(comment 1 "Lightning (Wiwynn / Facebook NVMe JBOF) / footprints 1434-1441 of 2563")
	)
	(layers
		(0 "F.Cu" signal "TOP")
		(4 "In1.Cu" signal "L2GND")
		(6 "In2.Cu" signal "L3")
		(8 "In3.Cu" signal "L4VCC")
		(10 "In4.Cu" signal "L5VCC")
		(12 "In5.Cu" signal "L6")
		(14 "In6.Cu" signal "L7GND")
		(2 "B.Cu" signal "BOTTOM")
		(9 "F.Adhes" user "F.Adhesive")
		(11 "B.Adhes" user "B.Adhesive")
		(13 "F.Paste" user "Package Geometry/Pastemask Top")
		(15 "B.Paste" user "Package Geometry/Pastemask Bottom")
		(5 "F.SilkS" user "Ref Des/Silkscreen Top")
		(7 "B.SilkS" user "Ref Des/Silkscreen Bottom")
		(1 "F.Mask" user "Board Geometry/Soldermask Top")
		(3 "B.Mask" user "Board Geometry/Soldermask Bottom")
		(17 "Dwgs.User" user "User.Drawings")
		(19 "Cmts.User" user "User.Comments")
		(21 "Eco1.User" user "User.Eco1")
		(23 "Eco2.User" user "User.Eco2")
		(25 "Edge.Cuts" user "Board Geometry/Outline")
		(27 "Margin" user)
		(31 "F.CrtYd" user "Package Geometry/Place Bound Top")
		(29 "B.CrtYd" user "Package Geometry/Place Bound Bottom")
		(35 "F.Fab" user "Ref Des/Assembly Top")
		(33 "B.Fab" user "Ref Des/Assembly Bottom")
	)
	(footprint ""
		(layer "F.Cu")
		(at 26.887932 -108.459016 -90)
		(property "Reference" "C287"
			(at 0 0 270)
			(layer "F.SilkS")
			(hide yes)
			(effects
				(font
					(size 1.27 1.27)
				)
			)
		)
		(property "Value" "SCD01U16V2KX-3GP"
			(at 1.1811 -2.7051 270)
			(unlocked yes)
			(layer "F.Fab")
			(hide yes)
			(effects
				(font
					(size 1.016 1.016)
					(thickness 0.1524)
				)
			)
		)
		(property "Device Type" "C402H22"
			(at 1.1811 -4.2291 270)
			(unlocked yes)
			(layer "F.Fab")
			(hide yes)
			(effects
				(font
					(size 1.016 1.016)
					(thickness 0.1524)
				)
			)
		)
		(duplicate_pad_numbers_are_jumpers no)
		(fp_rect
			(start -0.4318 0.9525)
			(end 0.4318 -0.9525)
			(stroke
				(width 0)
				(type default)
			)
			(fill no)
			(layer "F.CrtYd")
		)
		(fp_rect
			(start -0.4318 0.9525)
			(end 0.4318 -0.9525)
			(stroke
				(width 0)
				(type default)
			)
			(fill no)
			(layer "F.Fab")
		)
		(pad "1" smd custom
			(at 0 -0.4445 270)
			(size 0.1524 0.1524)
			(layers "F.Cu" "F.Mask" "F.Paste")
			(net "PCIE_REFCLK_S5_N")
			(options
				(clearance outline)
				(anchor circle)
			)
			(primitives
				(gr_poly
					(pts
						(arc
							(start 0.3048 -0.2032)
							(mid 0.275042 -0.275042)
							(end 0.2032 -0.3048)
						)
						(arc
							(start -0.2032 -0.3048)
							(mid -0.275042 -0.275042)
							(end -0.3048 -0.2032)
						)
						(arc
							(start -0.3048 0.2032)
							(mid -0.275042 0.275042)
							(end -0.2032 0.3048)
						)
						(arc
							(start 0.2032 0.3048)
							(mid 0.275042 0.275042)
							(end 0.3048 0.2032)
						)
					)
					(width 0)
					(fill yes)
				)
			)
		)
		(pad "2" smd custom
			(at 0 0.4445 270)
			(size 0.1524 0.1524)
			(layers "F.Cu" "F.Mask" "F.Paste")
			(net "BMC_REFCLK_N")
			(options
				(clearance outline)
				(anchor circle)
			)
			(primitives
				(gr_poly
					(pts
						(arc
							(start 0.3048 -0.2032)
							(mid 0.275042 -0.275042)
							(end 0.2032 -0.3048)
						)
						(arc
							(start -0.2032 -0.3048)
							(mid -0.275042 -0.275042)
							(end -0.3048 -0.2032)
						)
						(arc
							(start -0.3048 0.2032)
							(mid -0.275042 0.275042)
							(end -0.2032 0.3048)
						)
						(arc
							(start 0.2032 0.3048)
							(mid 0.275042 0.275042)
							(end 0.3048 0.2032)
						)
					)
					(width 0)
					(fill yes)
				)
			)
		)
	)
	(footprint ""
		(layer "F.Cu")
		(at 145.808192 -212.420454 180)
		(property "Reference" "C314"
			(at 0 0 180)
			(layer "F.SilkS")
			(hide yes)
			(effects
				(font
					(size 1.27 1.27)
				)
			)
		)
		(property "Value" "SCD22U10V2KX-1GP"
			(at 1.1811 -2.7051 180)
			(unlocked yes)
			(layer "F.Fab")
			(hide yes)
			(effects
				(font
					(size 1.016 1.016)
					(thickness 0.1524)
				)
			)
		)
		(property "Device Type" "C402H22"
			(at 1.1811 -4.2291 180)
			(unlocked yes)
			(layer "F.Fab")
			(hide yes)
			(effects
				(font
					(size 1.016 1.016)
					(thickness 0.1524)
				)
			)
		)
		(duplicate_pad_numbers_are_jumpers no)
		(fp_rect
			(start -0.4318 0.9525)
			(end 0.4318 -0.9525)
			(stroke
				(width 0)
				(type default)
			)
			(fill no)
			(layer "F.CrtYd")
		)
		(fp_rect
			(start -0.4318 0.9525)
			(end 0.4318 -0.9525)
			(stroke
				(width 0)
				(type default)
			)
			(fill no)
			(layer "F.Fab")
		)
		(pad "1" smd custom
			(at 0 -0.4445 180)
			(size 0.1524 0.1524)
			(layers "F.Cu" "F.Mask" "F.Paste")
			(net "PCIE_TX_CAP_N57")
			(options
				(clearance outline)
				(anchor circle)
			)
			(primitives
				(gr_poly
					(pts
						(arc
							(start 0.3048 -0.2032)
							(mid 0.275042 -0.275042)
							(end 0.2032 -0.3048)
						)
						(arc
							(start -0.2032 -0.3048)
							(mid -0.275042 -0.275042)
							(end -0.3048 -0.2032)
						)
						(arc
							(start -0.3048 0.2032)
							(mid -0.275042 0.275042)
							(end -0.2032 0.3048)
						)
						(arc
							(start 0.2032 0.3048)
							(mid 0.275042 0.275042)
							(end 0.3048 0.2032)
						)
					)
					(width 0)
					(fill yes)
				)
			)
		)
		(pad "2" smd custom
			(at 0 0.4445 180)
			(size 0.1524 0.1524)
			(layers "F.Cu" "F.Mask" "F.Paste")
			(net "PCIE_TX_N57")
			(options
				(clearance outline)
				(anchor circle)
			)
			(primitives
				(gr_poly
					(pts
						(arc
							(start 0.3048 -0.2032)
							(mid 0.275042 -0.275042)
							(end 0.2032 -0.3048)
						)
						(arc
							(start -0.2032 -0.3048)
							(mid -0.275042 -0.275042)
							(end -0.3048 -0.2032)
						)
						(arc
							(start -0.3048 0.2032)
							(mid -0.275042 0.275042)
							(end -0.2032 0.3048)
						)
						(arc
							(start 0.2032 0.3048)
							(mid 0.275042 0.275042)
							(end 0.3048 0.2032)
						)
					)
					(width 0)
					(fill yes)
				)
			)
		)
	)
	(footprint ""
		(layer "F.Cu")
		(at 122.8598 -98.7552 90)
		(property "Reference" "C245"
			(at 0 0 90)
			(layer "F.SilkS")
			(hide yes)
			(effects
				(font
					(size 1.27 1.27)
				)
			)
		)
		(property "Value" "SC220P50V3JN-GP"
			(at 0 -2.8194 90)
			(unlocked yes)
			(layer "F.Fab")
			(hide yes)
			(effects
				(font
					(size 1.016 1.016)
					(thickness 0.1524)
				)
			)
		)
		(property "Device Type" "C603H36"
			(at 0 -4.3434 90)
			(unlocked yes)
			(layer "F.Fab")
			(hide yes)
			(effects
				(font
					(size 1.016 1.016)
					(thickness 0.1524)
				)
			)
		)
		(duplicate_pad_numbers_are_jumpers no)
		(fp_line
			(start 0.508 0)
			(end -0.508 0)
			(stroke
				(width 0.2032)
				(type default)
			)
			(layer "F.SilkS")
		)
		(fp_rect
			(start -0.5842 1.3335)
			(end 0.5842 -1.3335)
			(stroke
				(width 0)
				(type default)
			)
			(fill no)
			(layer "F.CrtYd")
		)
		(fp_rect
			(start -0.5842 1.3335)
			(end 0.5842 -1.3335)
			(stroke
				(width 0)
				(type default)
			)
			(fill no)
			(layer "F.Fab")
		)
		(pad "1" smd custom
			(at 0 -0.762 90)
			(size 0.2159 0.2159)
			(layers "F.Cu" "F.Mask" "F.Paste")
			(net "BUF_I2C_SCL_2_R")
			(options
				(clearance outline)
				(anchor circle)
			)
			(primitives
				(gr_poly
					(pts
						(arc
							(start -0.3302 -0.4318)
							(mid -0.402042 -0.402042)
							(end -0.4318 -0.3302)
						)
						(arc
							(start -0.4318 0.3302)
							(mid -0.402042 0.402042)
							(end -0.3302 0.4318)
						)
						(arc
							(start 0.3302 0.4318)
							(mid 0.402042 0.402042)
							(end 0.4318 0.3302)
						)
						(arc
							(start 0.4318 -0.3302)
							(mid 0.402042 -0.402042)
							(end 0.3302 -0.4318)
						)
					)
					(width 0)
					(fill yes)
				)
			)
		)
		(pad "2" smd custom
			(at 0 0.762 90)
			(size 0.2159 0.2159)
			(layers "F.Cu" "F.Mask" "F.Paste")
			(net "GND")
			(options
				(clearance outline)
				(anchor circle)
			)
			(primitives
				(gr_poly
					(pts
						(arc
							(start -0.3302 -0.4318)
							(mid -0.402042 -0.402042)
							(end -0.4318 -0.3302)
						)
						(arc
							(start -0.4318 0.3302)
							(mid -0.402042 0.402042)
							(end -0.3302 0.4318)
						)
						(arc
							(start 0.3302 0.4318)
							(mid 0.402042 0.402042)
							(end 0.4318 0.3302)
						)
						(arc
							(start 0.4318 -0.3302)
							(mid 0.402042 -0.402042)
							(end 0.3302 -0.4318)
						)
					)
					(width 0)
					(fill yes)
				)
			)
		)
	)
	(footprint ""
		(layer "F.Cu")
		(at 41.783 -197.231 180)
		(property "Reference" "R884"
			(at 0 0 180)
			(layer "F.SilkS")
			(hide yes)
			(effects
				(font
					(size 1.27 1.27)
				)
			)
		)
		(property "Value" "0R2J-2-GP"
			(at 0.064008 -3.993896 180)
			(unlocked yes)
			(layer "F.Fab")
			(hide yes)
			(effects
				(font
					(size 1.016 1.016)
					(thickness 0.1524)
				)
			)
		)
		(property "Device Type" "R402H16"
			(at 0.064008 -5.517896 180)
			(unlocked yes)
			(layer "F.Fab")
			(hide yes)
			(effects
				(font
					(size 1.016 1.016)
					(thickness 0.1524)
				)
			)
		)
		(duplicate_pad_numbers_are_jumpers no)
		(fp_line
			(start 0.508 -0.9398)
			(end -0.508 -0.9398)
			(stroke
				(width 0.1524)
				(type default)
			)
			(layer "F.SilkS")
		)
		(fp_line
			(start -0.508 -0.9398)
			(end -0.508 0.9398)
			(stroke
				(width 0.1524)
				(type default)
			)
			(layer "F.SilkS")
		)
		(fp_rect
			(start -0.508 0.9398)
			(end 0.508 -0.9398)
			(stroke
				(width 0)
				(type default)
			)
			(fill no)
			(layer "F.CrtYd")
		)
		(fp_rect
			(start -0.508 0.9398)
			(end 0.508 -0.9398)
			(stroke
				(width 0)
				(type default)
			)
			(fill no)
			(layer "F.Fab")
		)
		(pad "1" smd custom
			(at 0 -0.4445 180)
			(size 0.1397 0.1397)
			(layers "F.Cu" "F.Mask" "F.Paste")
			(net "BMC_I2C6_C_FCB_SCL")
			(options
				(clearance outline)
				(anchor circle)
			)
			(primitives
				(gr_poly
					(pts
						(arc
							(start -0.1778 -0.2794)
							(mid -0.249642 -0.249642)
							(end -0.2794 -0.1778)
						)
						(arc
							(start -0.2794 0.1778)
							(mid -0.249642 0.249642)
							(end -0.1778 0.2794)
						)
						(arc
							(start 0.1778 0.2794)
							(mid 0.249642 0.249642)
							(end 0.2794 0.1778)
						)
						(arc
							(start 0.2794 -0.1778)
							(mid 0.249642 -0.249642)
							(end 0.1778 -0.2794)
						)
					)
					(width 0)
					(fill yes)
				)
			)
		)
		(pad "2" smd custom
			(at 0 0.4445 180)
			(size 0.1397 0.1397)
			(layers "F.Cu" "F.Mask" "F.Paste")
			(net "BMC_I2C6_C_FCB_SCL_R")
			(options
				(clearance outline)
				(anchor circle)
			)
			(primitives
				(gr_poly
					(pts
						(arc
							(start -0.1778 -0.2794)
							(mid -0.249642 -0.249642)
							(end -0.2794 -0.1778)
						)
						(arc
							(start -0.2794 0.1778)
							(mid -0.249642 0.249642)
							(end -0.1778 0.2794)
						)
						(arc
							(start 0.1778 0.2794)
							(mid 0.249642 0.249642)
							(end 0.2794 0.1778)
						)
						(arc
							(start 0.2794 -0.1778)
							(mid 0.249642 -0.249642)
							(end 0.1778 -0.2794)
						)
					)
					(width 0)
					(fill yes)
				)
			)
		)
	)
	(footprint ""
		(layer "F.Cu")
		(at 184.12206 -14.76502 180)
		(property "Reference" "R252"
			(at 0 0 180)
			(layer "F.SilkS")
			(hide yes)
			(effects
				(font
					(size 1.27 1.27)
				)
			)
		)
		(property "Value" "4K7R2F-GP"
			(at 0.064008 -3.993896 180)
			(unlocked yes)
			(layer "F.Fab")
			(hide yes)
			(effects
				(font
					(size 1.016 1.016)
					(thickness 0.1524)
				)
			)
		)
		(property "Device Type" "R402H16"
			(at 0.064008 -5.517896 180)
			(unlocked yes)
			(layer "F.Fab")
			(hide yes)
			(effects
				(font
					(size 1.016 1.016)
					(thickness 0.1524)
				)
			)
		)
		(duplicate_pad_numbers_are_jumpers no)
		(fp_line
			(start 0.508 -0.9398)
			(end -0.508 -0.9398)
			(stroke
				(width 0.1524)
				(type default)
			)
			(layer "F.SilkS")
		)
		(fp_line
			(start -0.508 -0.9398)
			(end -0.508 0.9398)
			(stroke
				(width 0.1524)
				(type default)
			)
			(layer "F.SilkS")
		)
		(fp_rect
			(start -0.508 0.9398)
			(end 0.508 -0.9398)
			(stroke
				(width 0)
				(type default)
			)
			(fill no)
			(layer "F.CrtYd")
		)
		(fp_rect
			(start -0.508 0.9398)
			(end 0.508 -0.9398)
			(stroke
				(width 0)
				(type default)
			)
			(fill no)
			(layer "F.Fab")
		)
		(pad "1" smd custom
			(at 0 -0.4445 180)
			(size 0.1397 0.1397)
			(layers "F.Cu" "F.Mask" "F.Paste")
			(net "P3V3_STBY")
			(options
				(clearance outline)
				(anchor circle)
			)
			(primitives
				(gr_poly
					(pts
						(arc
							(start -0.1778 -0.2794)
							(mid -0.249642 -0.249642)
							(end -0.2794 -0.1778)
						)
						(arc
							(start -0.2794 0.1778)
							(mid -0.249642 0.249642)
							(end -0.1778 0.2794)
						)
						(arc
							(start 0.1778 0.2794)
							(mid 0.249642 0.249642)
							(end 0.2794 0.1778)
						)
						(arc
							(start 0.2794 -0.1778)
							(mid 0.249642 -0.249642)
							(end 0.1778 -0.2794)
						)
					)
					(width 0)
					(fill yes)
				)
			)
		)
		(pad "2" smd custom
			(at 0 0.4445 180)
			(size 0.1397 0.1397)
			(layers "F.Cu" "F.Mask" "F.Paste")
			(net "CLK_P_4_R")
			(options
				(clearance outline)
				(anchor circle)
			)
			(primitives
				(gr_poly
					(pts
						(arc
							(start -0.1778 -0.2794)
							(mid -0.249642 -0.249642)
							(end -0.2794 -0.1778)
						)
						(arc
							(start -0.2794 0.1778)
							(mid -0.249642 0.249642)
							(end -0.1778 0.2794)
						)
						(arc
							(start 0.1778 0.2794)
							(mid 0.249642 0.249642)
							(end 0.2794 0.1778)
						)
						(arc
							(start 0.2794 -0.1778)
							(mid 0.249642 -0.249642)
							(end 0.1778 -0.2794)
						)
					)
					(width 0)
					(fill yes)
				)
			)
		)
	)
	(footprint ""
		(layer "F.Cu")
		(at 157.826202 -56.288432 -90)
		(property "Reference" "PC203"
			(at 0 0 270)
			(layer "F.SilkS")
			(hide yes)
			(effects
				(font
					(size 1.27 1.27)
				)
			)
		)
		(property "Value" "SC1KP50V2KX-1GP"
			(at 1.1811 -2.7051 270)
			(unlocked yes)
			(layer "F.Fab")
			(hide yes)
			(effects
				(font
					(size 1.016 1.016)
					(thickness 0.1524)
				)
			)
		)
		(property "Device Type" "C402H22"
			(at 1.1811 -4.2291 270)
			(unlocked yes)
			(layer "F.Fab")
			(hide yes)
			(effects
				(font
					(size 1.016 1.016)
					(thickness 0.1524)
				)
			)
		)
		(duplicate_pad_numbers_are_jumpers no)
		(fp_rect
			(start -0.4318 0.9525)
			(end 0.4318 -0.9525)
			(stroke
				(width 0)
				(type default)
			)
			(fill no)
			(layer "F.CrtYd")
		)
		(fp_rect
			(start -0.4318 0.9525)
			(end 0.4318 -0.9525)
			(stroke
				(width 0)
				(type default)
			)
			(fill no)
			(layer "F.Fab")
		)
		(pad "1" smd custom
			(at 0 -0.4445 270)
			(size 0.1524 0.1524)
			(layers "F.Cu" "F.Mask" "F.Paste")
			(net "P0V9_SW_R")
			(options
				(clearance outline)
				(anchor circle)
			)
			(primitives
				(gr_poly
					(pts
						(arc
							(start 0.3048 -0.2032)
							(mid 0.275042 -0.275042)
							(end 0.2032 -0.3048)
						)
						(arc
							(start -0.2032 -0.3048)
							(mid -0.275042 -0.275042)
							(end -0.3048 -0.2032)
						)
						(arc
							(start -0.3048 0.2032)
							(mid -0.275042 0.275042)
							(end -0.2032 0.3048)
						)
						(arc
							(start 0.2032 0.3048)
							(mid 0.275042 0.275042)
							(end 0.3048 0.2032)
						)
					)
					(width 0)
					(fill yes)
				)
			)
		)
		(pad "2" smd custom
			(at 0 0.4445 270)
			(size 0.1524 0.1524)
			(layers "F.Cu" "F.Mask" "F.Paste")
			(net "P0V9_VFB")
			(options
				(clearance outline)
				(anchor circle)
			)
			(primitives
				(gr_poly
					(pts
						(arc
							(start 0.3048 -0.2032)
							(mid 0.275042 -0.275042)
							(end 0.2032 -0.3048)
						)
						(arc
							(start -0.2032 -0.3048)
							(mid -0.275042 -0.275042)
							(end -0.3048 -0.2032)
						)
						(arc
							(start -0.3048 0.2032)
							(mid -0.275042 0.275042)
							(end -0.2032 0.3048)
						)
						(arc
							(start 0.2032 0.3048)
							(mid 0.275042 0.275042)
							(end 0.3048 0.2032)
						)
					)
					(width 0)
					(fill yes)
				)
			)
		)
	)
	(footprint ""
		(layer "F.Cu")
		(at 311.263792 -33.555686)
		(property "Reference" "C20"
			(at 0 0 0)
			(layer "F.SilkS")
			(hide yes)
			(effects
				(font
					(size 1.27 1.27)
				)
			)
		)
		(property "Value" "SCD22U10V2KX-1GP"
			(at 1.1811 -2.7051 0)
			(unlocked yes)
			(layer "F.Fab")
			(hide yes)
			(effects
				(font
					(size 1.016 1.016)
					(thickness 0.1524)
				)
			)
		)
		(property "Device Type" "C402H22"
			(at 1.1811 -4.2291 0)
			(unlocked yes)
			(layer "F.Fab")
			(hide yes)
			(effects
				(font
					(size 1.016 1.016)
					(thickness 0.1524)
				)
			)
		)
		(duplicate_pad_numbers_are_jumpers no)
		(fp_rect
			(start -0.4318 0.9525)
			(end 0.4318 -0.9525)
			(stroke
				(width 0)
				(type default)
			)
			(fill no)
			(layer "F.CrtYd")
		)
		(fp_rect
			(start -0.4318 0.9525)
			(end 0.4318 -0.9525)
			(stroke
				(width 0)
				(type default)
			)
			(fill no)
			(layer "F.Fab")
		)
		(pad "1" smd custom
			(at 0 -0.4445)
			(size 0.1524 0.1524)
			(layers "F.Cu" "F.Mask" "F.Paste")
			(net "PCIE_TX_CAP_N9")
			(options
				(clearance outline)
				(anchor circle)
			)
			(primitives
				(gr_poly
					(pts
						(arc
							(start 0.3048 -0.2032)
							(mid 0.275042 -0.275042)
							(end 0.2032 -0.3048)
						)
						(arc
							(start -0.2032 -0.3048)
							(mid -0.275042 -0.275042)
							(end -0.3048 -0.2032)
						)
						(arc
							(start -0.3048 0.2032)
							(mid -0.275042 0.275042)
							(end -0.2032 0.3048)
						)
						(arc
							(start 0.2032 0.3048)
							(mid 0.275042 0.275042)
							(end 0.3048 0.2032)
						)
					)
					(width 0)
					(fill yes)
				)
			)
		)
		(pad "2" smd custom
			(at 0 0.4445)
			(size 0.1524 0.1524)
			(layers "F.Cu" "F.Mask" "F.Paste")
			(net "PCIE_TX_N9")
			(options
				(clearance outline)
				(anchor circle)
			)
			(primitives
				(gr_poly
					(pts
						(arc
							(start 0.3048 -0.2032)
							(mid 0.275042 -0.275042)
							(end 0.2032 -0.3048)
						)
						(arc
							(start -0.2032 -0.3048)
							(mid -0.275042 -0.275042)
							(end -0.3048 -0.2032)
						)
						(arc
							(start -0.3048 0.2032)
							(mid -0.275042 0.275042)
							(end -0.2032 0.3048)
						)
						(arc
							(start 0.2032 0.3048)
							(mid 0.275042 0.275042)
							(end 0.3048 0.2032)
						)
					)
					(width 0)
					(fill yes)
				)
			)
		)
	)
	(footprint ""
		(layer "F.Cu")
		(at 179.9844 -61.595)
		(property "Reference" "C559"
			(at 0 0 0)
			(layer "F.SilkS")
			(hide yes)
			(effects
				(font
					(size 1.27 1.27)
				)
			)
		)
		(property "Value" "SC4D7U16V5KX-1-GP"
			(at -0.0762 -6.1214 0)
			(unlocked yes)
			(layer "F.Fab")
			(hide yes)
			(effects
				(font
					(size 1.016 1.016)
					(thickness 0.1524)
				)
			)
		)
		(property "Device Type" "C805H56"
			(at -0.0762 -8.1534 0)
			(unlocked yes)
			(layer "F.Fab")
			(hide yes)
			(effects
				(font
					(size 1.016 1.016)
					(thickness 0.1524)
				)
			)
		)
		(duplicate_pad_numbers_are_jumpers no)
		(fp_line
			(start 0.635 0)
			(end -0.635 0)
			(stroke
				(width 0.508)
				(type default)
			)
			(layer "F.SilkS")
		)
		(fp_rect
			(start -0.9652 1.778)
			(end 0.9652 -1.778)
			(stroke
				(width 0)
				(type default)
			)
			(fill no)
			(layer "F.CrtYd")
		)
		(fp_poly
			(pts
				(xy -0.9652 -1.778) (xy 0.9652 -1.778) (xy 0.9652 1.778) (xy -0.9652 1.778)
			)
			(stroke
				(width 0)
				(type default)
			)
			(fill no)
			(layer "F.Fab")
		)
		(pad "1" smd rect
			(at 0 -0.9652)
			(size 1.397 1.143)
			(layers "F.Cu" "F.Mask" "F.Paste")
			(net "DUT_AVD_PCIE")
		)
		(pad "2" smd rect
			(at 0 0.9652)
			(size 1.397 1.143)
			(layers "F.Cu" "F.Mask" "F.Paste")
			(net "GND")
		)
	)
)
